# S9S_MB_2U (Grand Teton) — schematic netlist excerpt (pin names and nets, part order shuffled) for the footprints in the layout excerpt that follows; sources: Cadence DE-HDL packaged netlist, KiCad conversion of 03242023_DA0F0TMBIJ0_F0T_Motherboard_J_brd_V01_OCP.brd

D7  BAT547F  IC  pkg SOT23_123XB  page 260 : \1\ = P3V3 ; \3\ = P5V
C876  Q_CAP_DIFFBUS  DIFF BUS_0.22UF 6.3V 20% X6S  pkg C0201  page 174 : \1\ = P5E_CPU0_PE3_TX_C_DN<12> ; \2\ = P5E_CPU0_PE3_TX_DN<12>
C261  Q_CAP  10UF 6.3V 20% X6S  pkg C0402  page 77 : A = PVCCIN_CPU1 ; B = GND

(kicad_pcb
	(version 20260206)
	(generator "pcbnew")
	(generator_version "10.0")
	(general
		(thickness 1.6)
		(legacy_teardrops no)
	)
	(paper "A4")
	(title_block
		(title "03242023_DA0F0TMBIJ0_F0T_Motherboard_J_brd_V01_OCP.brd")
		(comment 1 "Grand Teton / footprints 2502-2504 of 6105")
	)
	(layers
		(0 "F.Cu" signal "TOP")
		(4 "In1.Cu" signal "GND")
		(6 "In2.Cu" signal "IN1")
		(8 "In3.Cu" signal "GND1")
		(10 "In4.Cu" signal "IN2")
		(12 "In5.Cu" signal "GND2")
		(14 "In6.Cu" signal "IN3")
		(16 "In7.Cu" signal "GND3")
		(18 "In8.Cu" signal "VCC")
		(20 "In9.Cu" signal "VCC1")
		(22 "In10.Cu" signal "GND4")
		(24 "In11.Cu" signal "IN4")
		(26 "In12.Cu" signal "GND5")
		(28 "In13.Cu" signal "IN5")
		(30 "In14.Cu" signal "GND6")
		(32 "In15.Cu" signal "IN6")
		(34 "In16.Cu" signal "GND7")
		(2 "B.Cu" signal "BOTTOM")
		(9 "F.Adhes" user "F.Adhesive")
		(11 "B.Adhes" user "B.Adhesive")
		(13 "F.Paste" user "Package Geometry/Pastemask Top")
		(15 "B.Paste" user "Package Geometry/Pastemask Bottom")
		(5 "F.SilkS" user "Ref Des/Silkscreen Top")
		(7 "B.SilkS" user "Ref Des/Silkscreen Bottom")
		(1 "F.Mask" user "Board Geometry/Soldermask Top")
		(3 "B.Mask" user "Board Geometry/Soldermask Bottom")
		(17 "Dwgs.User" user "User.Drawings")
		(19 "Cmts.User" user "User.Comments")
		(21 "Eco1.User" user "User.Eco1")
		(23 "Eco2.User" user "User.Eco2")
		(25 "Edge.Cuts" user "Board Geometry/Outline")
		(27 "Margin" user)
		(31 "F.CrtYd" user "Package Geometry/Place Bound Top")
		(29 "B.CrtYd" user "Package Geometry/Place Bound Bottom")
		(35 "F.Fab" user "Ref Des/Assembly Top")
		(33 "B.Fab" user "Ref Des/Assembly Bottom")
	)
	(footprint ""
		(layer "F.Cu")
		(at 104.3432 -252.956568 -90)
		(property "Reference" "C261"
			(at 0 0 270)
			(layer "F.SilkS")
			(hide yes)
			(effects
				(font
					(size 1.27 1.27)
				)
			)
		)
		(property "Value" ""
			(at 0 0 270)
			(layer "F.Fab")
			(effects
				(font
					(size 1.27 1.27)
				)
			)
		)
		(duplicate_pad_numbers_are_jumpers no)
		(fp_line
			(start -0.7874 0.4064)
			(end -0.7874 -0.4064)
			(stroke
				(width 0.1524)
				(type default)
			)
			(layer "F.SilkS")
		)
		(fp_line
			(start 0.7874 0.4064)
			(end -0.7874 0.4064)
			(stroke
				(width 0.1524)
				(type default)
			)
			(layer "F.SilkS")
		)
		(fp_line
			(start -0.7874 -0.4064)
			(end 0.7874 -0.4064)
			(stroke
				(width 0.1524)
				(type default)
			)
			(layer "F.SilkS")
		)
		(fp_line
			(start 0.7874 -0.4064)
			(end 0.7874 0.4064)
			(stroke
				(width 0.1524)
				(type default)
			)
			(layer "F.SilkS")
		)
		(fp_line
			(start -0.67945 0.3048)
			(end -0.67945 -0.305054)
			(stroke
				(width 0.1)
				(type default)
			)
			(layer "F.Fab")
		)
		(fp_line
			(start -0.12065 0.3048)
			(end -0.67945 0.3048)
			(stroke
				(width 0.1)
				(type default)
			)
			(layer "F.Fab")
		)
		(fp_line
			(start 0.120396 0.3048)
			(end 0.120396 0.2794)
			(stroke
				(width 0.1)
				(type default)
			)
			(layer "F.Fab")
		)
		(fp_line
			(start 0.67945 0.3048)
			(end 0.120396 0.3048)
			(stroke
				(width 0.1)
				(type default)
			)
			(layer "F.Fab")
		)
		(fp_line
			(start -0.12065 0.2794)
			(end -0.12065 0.3048)
			(stroke
				(width 0.1)
				(type default)
			)
			(layer "F.Fab")
		)
		(fp_line
			(start 0.120396 0.2794)
			(end -0.12065 0.2794)
			(stroke
				(width 0.1)
				(type default)
			)
			(layer "F.Fab")
		)
		(fp_line
			(start -0.12065 -0.2794)
			(end 0.12065 -0.2794)
			(stroke
				(width 0.1)
				(type default)
			)
			(layer "F.Fab")
		)
		(fp_line
			(start 0.12065 -0.2794)
			(end 0.12065 -0.3048)
			(stroke
				(width 0.1)
				(type default)
			)
			(layer "F.Fab")
		)
		(fp_line
			(start 0.12065 -0.3048)
			(end 0.67945 -0.3048)
			(stroke
				(width 0.1)
				(type default)
			)
			(layer "F.Fab")
		)
		(fp_line
			(start 0.67945 -0.3048)
			(end 0.67945 0.3048)
			(stroke
				(width 0.1)
				(type default)
			)
			(layer "F.Fab")
		)
		(fp_line
			(start -0.67945 -0.305054)
			(end -0.12065 -0.305054)
			(stroke
				(width 0.1)
				(type default)
			)
			(layer "F.Fab")
		)
		(fp_line
			(start -0.12065 -0.305054)
			(end -0.12065 -0.2794)
			(stroke
				(width 0.1)
				(type default)
			)
			(layer "F.Fab")
		)
		(pad "1" smd circle
			(at -0.40005 0 270)
			(size 0 0)
			(layers "F.Cu" "F.Mask" "F.Paste")
			(net "PVCCIN_CPU1")
		)
		(pad "2" smd circle
			(at 0.40005 0 270)
			(size 0 0)
			(layers "F.Cu" "F.Mask" "F.Paste")
			(net "GND")
		)
	)
	(footprint ""
		(layer "F.Cu")
		(at 421.801544 -46.5455 -90)
		(property "Reference" "D7"
			(at 2.457958 1.281684 0)
			(unlocked yes)
			(layer "F.SilkS")
			(effects
				(font
					(size 0.7874 0.5842)
					(thickness 0.1524)
				)
				(justify left)
			)
		)
		(property "Value" ""
			(at 0 0 270)
			(layer "F.Fab")
			(effects
				(font
					(size 1.27 1.27)
				)
			)
		)
		(duplicate_pad_numbers_are_jumpers no)
		(fp_line
			(start -1.584198 1.500124)
			(end 1.584198 1.500124)
			(stroke
				(width 0.1524)
				(type default)
			)
			(layer "F.SilkS")
		)
		(fp_line
			(start 1.584198 1.500124)
			(end 1.584198 -1.500124)
			(stroke
				(width 0.1524)
				(type default)
			)
			(layer "F.SilkS")
		)
		(fp_line
			(start -1.584198 -1.500124)
			(end -1.584198 1.500124)
			(stroke
				(width 0.1524)
				(type default)
			)
			(layer "F.SilkS")
		)
		(fp_line
			(start 1.584198 -1.500124)
			(end -1.584198 -1.500124)
			(stroke
				(width 0.1524)
				(type default)
			)
			(layer "F.SilkS")
		)
		(fp_line
			(start -0.700024 1.500124)
			(end 0.700024 1.500124)
			(stroke
				(width 0.1)
				(type default)
			)
			(layer "F.Fab")
		)
		(fp_line
			(start 0.700024 1.500124)
			(end 0.700024 -1.500124)
			(stroke
				(width 0.1)
				(type default)
			)
			(layer "F.Fab")
		)
		(fp_line
			(start -0.700024 -1.500124)
			(end -0.700024 1.500124)
			(stroke
				(width 0.1)
				(type default)
			)
			(layer "F.Fab")
		)
		(fp_line
			(start 0.700024 -1.500124)
			(end -0.700024 -1.500124)
			(stroke
				(width 0.1)
				(type default)
			)
			(layer "F.Fab")
		)
		(pad "1" smd rect
			(at -0.999998 -0.94996 180)
			(size 0.8128 0.9144)
			(layers "F.Cu" "F.Mask" "F.Paste")
			(net "P3V3")
		)
		(pad "2" smd rect
			(at -0.999998 0.94996 180)
			(size 0.8128 0.9144)
			(layers "F.Cu" "F.Mask" "F.Paste")
			(net "Net_8589")
		)
		(pad "3" smd rect
			(at 0.999998 0 180)
			(size 0.8128 0.9144)
			(layers "F.Cu" "F.Mask" "F.Paste")
			(net "P5V")
		)
	)
	(footprint ""
		(layer "F.Cu")
		(at 381.93345 -408.517344 -90)
		(property "Reference" "C876"
			(at 0 0 270)
			(layer "F.SilkS")
			(hide yes)
			(effects
				(font
					(size 1.27 1.27)
				)
			)
		)
		(property "Value" ""
			(at 0 0 270)
			(layer "F.Fab")
			(effects
				(font
					(size 1.27 1.27)
				)
			)
		)
		(duplicate_pad_numbers_are_jumpers no)
		(fp_line
			(start -0.299974 0.150114)
			(end -0.299974 -0.150114)
			(stroke
				(width 0.1)
				(type default)
			)
			(layer "F.Fab")
		)
		(fp_line
			(start 0.299974 0.150114)
			(end -0.299974 0.150114)
			(stroke
				(width 0.1)
				(type default)
			)
			(layer "F.Fab")
		)
		(fp_line
			(start -0.299974 -0.150114)
			(end 0.299974 -0.150114)
			(stroke
				(width 0.1)
				(type default)
			)
			(layer "F.Fab")
		)
		(fp_line
			(start 0.299974 -0.150114)
			(end 0.299974 0.150114)
			(stroke
				(width 0.1)
				(type default)
			)
			(layer "F.Fab")
		)
		(pad "1" smd rect
			(at -0.2667 0 270)
			(size 0.3048 0.381)
			(layers "F.Cu" "F.Mask" "F.Paste")
			(net "P5E_CPU0_PE3_TX_C_DN<12>")
		)
		(pad "2" smd rect
			(at 0.2667 0 270)
			(size 0.3048 0.381)
			(layers "F.Cu" "F.Mask" "F.Paste")
			(net "P5E_CPU0_PE3_TX_DN<12>")
		)
	)
)
